(kicad_pcb
	(version 20260206)
	(generator "pcbnew")
	(generator_version "10.0")
	(general
		(thickness 1.6)
		(legacy_teardrops no)
	)
	(paper "A4")
	(title_block
		(title "03242023_DA0F0TMBIJ0_F0T_Motherboard_J_brd_V01_OCP.brd")
		(comment 1 "Grand Teton / footprints 274-279 of 6105")
	)
	(layers
		(0 "F.Cu" signal "TOP")
		(4 "In1.Cu" signal "GND")
		(6 "In2.Cu" signal "IN1")
		(8 "In3.Cu" signal "GND1")
		(10 "In4.Cu" signal "IN2")
		(12 "In5.Cu" signal "GND2")
		(14 "In6.Cu" signal "IN3")
		(16 "In7.Cu" signal "GND3")
		(18 "In8.Cu" signal "VCC")
		(20 "In9.Cu" signal "VCC1")
		(22 "In10.Cu" signal "GND4")
		(24 "In11.Cu" signal "IN4")
		(26 "In12.Cu" signal "GND5")
		(28 "In13.Cu" signal "IN5")
		(30 "In14.Cu" signal "GND6")
		(32 "In15.Cu" signal "IN6")
		(34 "In16.Cu" signal "GND7")
		(2 "B.Cu" signal "BOTTOM")
		(9 "F.Adhes" user "F.Adhesive")
		(11 "B.Adhes" user "B.Adhesive")
		(13 "F.Paste" user "Package Geometry/Pastemask Top")
		(15 "B.Paste" user "Package Geometry/Pastemask Bottom")
		(5 "F.SilkS" user "Ref Des/Silkscreen Top")
		(7 "B.SilkS" user "Ref Des/Silkscreen Bottom")
		(1 "F.Mask" user "Board Geometry/Soldermask Top")
		(3 "B.Mask" user "Board Geometry/Soldermask Bottom")
		(17 "Dwgs.User" user "User.Drawings")
		(19 "Cmts.User" user "User.Comments")
		(21 "Eco1.User" user "User.Eco1")
		(23 "Eco2.User" user "User.Eco2")
		(25 "Edge.Cuts" user "Board Geometry/Outline")
		(27 "Margin" user)
		(31 "F.CrtYd" user "Package Geometry/Place Bound Top")
		(29 "B.CrtYd" user "Package Geometry/Place Bound Bottom")
		(35 "F.Fab" user "Ref Des/Assembly Top")
		(33 "B.Fab" user "Ref Des/Assembly Bottom")
	)
	(footprint ""
		(layer "F.Cu")
		(at 144.61236 -92.634308 -90)
		(property "Reference" "R4051"
			(at 0 0 270)
			(layer "F.SilkS")
			(hide yes)
			(effects
				(font
					(size 1.27 1.27)
				)
			)
		)
		(property "Value" ""
			(at 0 0 270)
			(layer "F.Fab")
			(effects
				(font
					(size 1.27 1.27)
				)
			)
		)
		(duplicate_pad_numbers_are_jumpers no)
		(fp_line
			(start -0.7874 0.4064)
			(end -0.7874 -0.4064)
			(stroke
				(width 0.1524)
				(type default)
			)
			(layer "F.SilkS")
		)
		(fp_line
			(start 0.7874 0.4064)
			(end -0.7874 0.4064)
			(stroke
				(width 0.1524)
				(type default)
			)
			(layer "F.SilkS")
		)
		(fp_line
			(start -0.7874 -0.4064)
			(end 0.7874 -0.4064)
			(stroke
				(width 0.1524)
				(type default)
			)
			(layer "F.SilkS")
		)
		(fp_line
			(start 0.7874 -0.4064)
			(end 0.7874 0.4064)
			(stroke
				(width 0.1524)
				(type default)
			)
			(layer "F.SilkS")
		)
		(fp_line
			(start -0.67945 0.3048)
			(end -0.67945 -0.305054)
			(stroke
				(width 0.1)
				(type default)
			)
			(layer "F.Fab")
		)
		(fp_line
			(start -0.12065 0.3048)
			(end -0.67945 0.3048)
			(stroke
				(width 0.1)
				(type default)
			)
			(layer "F.Fab")
		)
		(fp_line
			(start 0.120396 0.3048)
			(end 0.120396 0.2794)
			(stroke
				(width 0.1)
				(type default)
			)
			(layer "F.Fab")
		)
		(fp_line
			(start 0.67945 0.3048)
			(end 0.120396 0.3048)
			(stroke
				(width 0.1)
				(type default)
			)
			(layer "F.Fab")
		)
		(fp_line
			(start -0.12065 0.2794)
			(end -0.12065 0.3048)
			(stroke
				(width 0.1)
				(type default)
			)
			(layer "F.Fab")
		)
		(fp_line
			(start 0.120396 0.2794)
			(end -0.12065 0.2794)
			(stroke
				(width 0.1)
				(type default)
			)
			(layer "F.Fab")
		)
		(fp_line
			(start -0.12065 -0.2794)
			(end 0.12065 -0.2794)
			(stroke
				(width 0.1)
				(type default)
			)
			(layer "F.Fab")
		)
		(fp_line
			(start 0.12065 -0.2794)
			(end 0.12065 -0.3048)
			(stroke
				(width 0.1)
				(type default)
			)
			(layer "F.Fab")
		)
		(fp_line
			(start 0.12065 -0.3048)
			(end 0.67945 -0.3048)
			(stroke
				(width 0.1)
				(type default)
			)
			(layer "F.Fab")
		)
		(fp_line
			(start 0.67945 -0.3048)
			(end 0.67945 0.3048)
			(stroke
				(width 0.1)
				(type default)
			)
			(layer "F.Fab")
		)
		(fp_line
			(start -0.67945 -0.305054)
			(end -0.12065 -0.305054)
			(stroke
				(width 0.1)
				(type default)
			)
			(layer "F.Fab")
		)
		(fp_line
			(start -0.12065 -0.305054)
			(end -0.12065 -0.2794)
			(stroke
				(width 0.1)
				(type default)
			)
			(layer "F.Fab")
		)
		(pad "1" smd circle
			(at -0.40005 0 270)
			(size 0 0)
			(layers "F.Cu" "F.Mask" "F.Paste")
			(net "H_CPU_ERR1_LVC2_R_N")
		)
		(pad "2" smd circle
			(at 0.40005 0 270)
			(size 0 0)
			(layers "F.Cu" "F.Mask" "F.Paste")
			(net "H_CPU_ERR1_LVC2_N")
		)
	)
	(footprint ""
		(layer "F.Cu")
		(at 259.710936 -38.738556 90)
		(property "Reference" "PD114"
			(at 4.87172 -1.177036 0)
			(unlocked yes)
			(layer "F.SilkS")
			(effects
				(font
					(size 0.7874 0.5842)
					(thickness 0.1524)
				)
				(justify left)
			)
		)
		(property "Value" ""
			(at 0 0 90)
			(layer "F.Fab")
			(effects
				(font
					(size 1.27 1.27)
				)
			)
		)
		(duplicate_pad_numbers_are_jumpers no)
		(fp_line
			(start 2.631186 -0.999998)
			(end -2.250186 -0.999998)
			(stroke
				(width 0.1524)
				(type default)
			)
			(layer "F.SilkS")
		)
		(fp_line
			(start -2.250186 -0.999998)
			(end -2.250186 0.999998)
			(stroke
				(width 0.1524)
				(type default)
			)
			(layer "F.SilkS")
		)
		(fp_line
			(start 0.381 -0.4318)
			(end 0.381 0.3302)
			(stroke
				(width 0.1524)
				(type default)
			)
			(layer "F.SilkS")
		)
		(fp_line
			(start -0.381 -0.4318)
			(end 0.381 -0.0508)
			(stroke
				(width 0.1524)
				(type default)
			)
			(layer "F.SilkS")
		)
		(fp_line
			(start 0.381 -0.0508)
			(end 0.635 -0.0508)
			(stroke
				(width 0.1524)
				(type default)
			)
			(layer "F.SilkS")
		)
		(fp_line
			(start 0.381 -0.0508)
			(end -0.381 0.3302)
			(stroke
				(width 0.1524)
				(type default)
			)
			(layer "F.SilkS")
		)
		(fp_line
			(start -0.381 -0.0508)
			(end -0.6604 -0.0508)
			(stroke
				(width 0.1524)
				(type default)
			)
			(layer "F.SilkS")
		)
		(fp_line
			(start -0.381 0.3302)
			(end -0.381 -0.4318)
			(stroke
				(width 0.1524)
				(type default)
			)
			(layer "F.SilkS")
		)
		(fp_line
			(start 2.631186 0.999998)
			(end 2.631186 -0.999998)
			(stroke
				(width 0.1524)
				(type default)
			)
			(layer "F.SilkS")
		)
		(fp_line
			(start -2.250186 0.999998)
			(end 2.631186 0.999998)
			(stroke
				(width 0.1524)
				(type default)
			)
			(layer "F.SilkS")
		)
		(fp_rect
			(start 2.1844 -0.9652)
			(end 2.6162 1.016)
			(stroke
				(width 0)
				(type default)
			)
			(fill yes)
			(layer "F.SilkS")
		)
		(fp_line
			(start 1.450086 -0.999998)
			(end -1.450086 -0.999998)
			(stroke
				(width 0.1)
				(type default)
			)
			(layer "F.Fab")
		)
		(fp_line
			(start -1.450086 -0.999998)
			(end -1.450086 0.999998)
			(stroke
				(width 0.1)
				(type default)
			)
			(layer "F.Fab")
		)
		(fp_line
			(start 1.450086 0.999998)
			(end 1.450086 -0.999998)
			(stroke
				(width 0.1)
				(type default)
			)
			(layer "F.Fab")
		)
		(fp_line
			(start -1.450086 0.999998)
			(end 1.450086 0.999998)
			(stroke
				(width 0.1)
				(type default)
			)
			(layer "F.Fab")
		)
		(fp_text user "-"
			(at 2.4384 -0.22225 90)
			(unlocked yes)
			(layer "F.SilkS")
			(effects
				(font
					(size 1.905 1.4224)
					(thickness 0.1524)
				)
				(justify left)
			)
		)
		(fp_text user "+"
			(at -3.83921 1.491234 90)
			(unlocked yes)
			(layer "F.SilkS")
			(effects
				(font
					(size 1.905 1.4224)
					(thickness 0.1524)
				)
				(justify left)
			)
		)
		(fp_text user "-"
			(at 2.4384 -0.22225 90)
			(unlocked yes)
			(layer "F.Fab")
			(effects
				(font
					(size 1.905 1.4224)
					(thickness 0.1524)
				)
				(justify left)
			)
		)
		(fp_text user "+"
			(at -3.4798 -0.22225 90)
			(unlocked yes)
			(layer "F.Fab")
			(effects
				(font
					(size 1.905 1.4224)
					(thickness 0.1524)
				)
				(justify left)
			)
		)
		(pad "A" smd rect
			(at -1.450086 0 90)
			(size 1.3208 1.4224)
			(layers "F.Cu" "F.Mask" "F.Paste")
			(net "GND")
		)
		(pad "C" smd rect
			(at 1.450086 0 90)
			(size 1.3208 1.4224)
			(layers "F.Cu" "F.Mask" "F.Paste")
			(net "P12V_AUX")
		)
	)
	(footprint ""
		(layer "F.Cu")
		(at 19.19859 -385.865624 90)
		(property "Reference" "R4659"
			(at 0 0 90)
			(layer "F.SilkS")
			(hide yes)
			(effects
				(font
					(size 1.27 1.27)
				)
			)
		)
		(property "Value" ""
			(at 0 0 90)
			(layer "F.Fab")
			(effects
				(font
					(size 1.27 1.27)
				)
			)
		)
		(duplicate_pad_numbers_are_jumpers no)
		(fp_line
			(start -0.7874 -0.4064)
			(end 0.7874 -0.4064)
			(stroke
				(width 0.1524)
				(type default)
			)
			(layer "F.SilkS")
		)
		(fp_line
			(start 0.7874 0.4064)
			(end -0.001524 0.4064)
			(stroke
				(width 0.1524)
				(type default)
			)
			(layer "F.SilkS")
		)
		(fp_line
			(start -0.7874 0.4064)
			(end -0.7874 -0.4064)
			(stroke
				(width 0.1524)
				(type default)
			)
			(layer "F.SilkS")
		)
		(fp_line
			(start -0.12065 -0.305054)
			(end -0.12065 -0.2794)
			(stroke
				(width 0.1)
				(type default)
			)
			(layer "F.Fab")
		)
		(fp_line
			(start -0.67945 -0.305054)
			(end -0.12065 -0.305054)
			(stroke
				(width 0.1)
				(type default)
			)
			(layer "F.Fab")
		)
		(fp_line
			(start 0.67945 -0.3048)
			(end 0.67945 0.3048)
			(stroke
				(width 0.1)
				(type default)
			)
			(layer "F.Fab")
		)
		(fp_line
			(start 0.12065 -0.3048)
			(end 0.67945 -0.3048)
			(stroke
				(width 0.1)
				(type default)
			)
			(layer "F.Fab")
		)
		(fp_line
			(start 0.12065 -0.2794)
			(end 0.12065 -0.3048)
			(stroke
				(width 0.1)
				(type default)
			)
			(layer "F.Fab")
		)
		(fp_line
			(start -0.12065 -0.2794)
			(end 0.12065 -0.2794)
			(stroke
				(width 0.1)
				(type default)
			)
			(layer "F.Fab")
		)
		(fp_line
			(start 0.120396 0.2794)
			(end -0.12065 0.2794)
			(stroke
				(width 0.1)
				(type default)
			)
			(layer "F.Fab")
		)
		(fp_line
			(start -0.12065 0.2794)
			(end -0.12065 0.3048)
			(stroke
				(width 0.1)
				(type default)
			)
			(layer "F.Fab")
		)
		(fp_line
			(start 0.67945 0.3048)
			(end 0.120396 0.3048)
			(stroke
				(width 0.1)
				(type default)
			)
			(layer "F.Fab")
		)
		(fp_line
			(start 0.120396 0.3048)
			(end 0.120396 0.2794)
			(stroke
				(width 0.1)
				(type default)
			)
			(layer "F.Fab")
		)
		(fp_line
			(start -0.12065 0.3048)
			(end -0.67945 0.3048)
			(stroke
				(width 0.1)
				(type default)
			)
			(layer "F.Fab")
		)
		(fp_line
			(start -0.67945 0.3048)
			(end -0.67945 -0.305054)
			(stroke
				(width 0.1)
				(type default)
			)
			(layer "F.Fab")
		)
		(pad "1" smd rect
			(at -0.40005 0 270)
			(size 0.4572 0.508)
			(layers "F.Cu" "F.Mask" "F.Paste")
			(net "P2E_MB_BMC_TX_C_DP<0>")
		)
		(pad "2" smd rect
			(at 0.40005 0 270)
			(size 0.4572 0.508)
			(layers "F.Cu" "F.Mask" "F.Paste")
			(net "P2E_MB_BMC_TX_C_R1_DP<0>")
		)
	)
	(footprint ""
		(layer "F.Cu")
		(at 307.14188 -50.878486 180)
		(property "Reference" "R1338"
			(at 0 0 180)
			(layer "F.SilkS")
			(hide yes)
			(effects
				(font
					(size 1.27 1.27)
				)
			)
		)
		(property "Value" ""
			(at 0 0 180)
			(layer "F.Fab")
			(effects
				(font
					(size 1.27 1.27)
				)
			)
		)
		(duplicate_pad_numbers_are_jumpers no)
		(fp_line
			(start 0.7874 0.4064)
			(end -0.7874 0.4064)
			(stroke
				(width 0.1524)
				(type default)
			)
			(layer "F.SilkS")
		)
		(fp_line
			(start 0.7874 -0.4064)
			(end 0.7874 0.4064)
			(stroke
				(width 0.1524)
				(type default)
			)
			(layer "F.SilkS")
		)
		(fp_line
			(start -0.7874 0.4064)
			(end -0.7874 -0.4064)
			(stroke
				(width 0.1524)
				(type default)
			)
			(layer "F.SilkS")
		)
		(fp_line
			(start -0.7874 -0.4064)
			(end 0.7874 -0.4064)
			(stroke
				(width 0.1524)
				(type default)
			)
			(layer "F.SilkS")
		)
		(fp_line
			(start 0.67945 0.3048)
			(end 0.120396 0.3048)
			(stroke
				(width 0.1)
				(type default)
			)
			(layer "F.Fab")
		)
		(fp_line
			(start 0.67945 -0.3048)
			(end 0.67945 0.3048)
			(stroke
				(width 0.1)
				(type default)
			)
			(layer "F.Fab")
		)
		(fp_line
			(start 0.12065 -0.2794)
			(end 0.12065 -0.3048)
			(stroke
				(width 0.1)
				(type default)
			)
			(layer "F.Fab")
		)
		(fp_line
			(start 0.12065 -0.3048)
			(end 0.67945 -0.3048)
			(stroke
				(width 0.1)
				(type default)
			)
			(layer "F.Fab")
		)
		(fp_line
			(start 0.120396 0.3048)
			(end 0.120396 0.2794)
			(stroke
				(width 0.1)
				(type default)
			)
			(layer "F.Fab")
		)
		(fp_line
			(start 0.120396 0.2794)
			(end -0.12065 0.2794)
			(stroke
				(width 0.1)
				(type default)
			)
			(layer "F.Fab")
		)
		(fp_line
			(start -0.12065 0.3048)
			(end -0.67945 0.3048)
			(stroke
				(width 0.1)
				(type default)
			)
			(layer "F.Fab")
		)
		(fp_line
			(start -0.12065 0.2794)
			(end -0.12065 0.3048)
			(stroke
				(width 0.1)
				(type default)
			)
			(layer "F.Fab")
		)
		(fp_line
			(start -0.12065 -0.2794)
			(end 0.12065 -0.2794)
			(stroke
				(width 0.1)
				(type default)
			)
			(layer "F.Fab")
		)
		(fp_line
			(start -0.12065 -0.305054)
			(end -0.12065 -0.2794)
			(stroke
				(width 0.1)
				(type default)
			)
			(layer "F.Fab")
		)
		(fp_line
			(start -0.67945 0.3048)
			(end -0.67945 -0.305054)
			(stroke
				(width 0.1)
				(type default)
			)
			(layer "F.Fab")
		)
		(fp_line
			(start -0.67945 -0.305054)
			(end -0.12065 -0.305054)
			(stroke
				(width 0.1)
				(type default)
			)
			(layer "F.Fab")
		)
		(pad "1" smd circle
			(at -0.40005 0 180)
			(size 0 0)
			(layers "F.Cu" "F.Mask" "F.Paste")
			(net "FM_PCH_BIOS_RCVR_MODE")
		)
		(pad "2" smd circle
			(at 0.40005 0 180)
			(size 0 0)
			(layers "F.Cu" "F.Mask" "F.Paste")
			(net "GND")
		)
	)
	(footprint ""
		(layer "F.Cu")
		(at 304.09896 -433.04587 90)
		(property "Reference" "R4140"
			(at 0 0 90)
			(layer "F.SilkS")
			(hide yes)
			(effects
				(font
					(size 1.27 1.27)
				)
			)
		)
		(property "Value" ""
			(at 0 0 90)
			(layer "F.Fab")
			(effects
				(font
					(size 1.27 1.27)
				)
			)
		)
		(duplicate_pad_numbers_are_jumpers no)
		(fp_line
			(start 0.7874 -0.4064)
			(end 0.7874 0.4064)
			(stroke
				(width 0.1524)
				(type default)
			)
			(layer "F.SilkS")
		)
		(fp_line
			(start -0.7874 -0.4064)
			(end 0.7874 -0.4064)
			(stroke
				(width 0.1524)
				(type default)
			)
			(layer "F.SilkS")
		)
		(fp_line
			(start 0.7874 0.4064)
			(end -0.7874 0.4064)
			(stroke
				(width 0.1524)
				(type default)
			)
			(layer "F.SilkS")
		)
		(fp_line
			(start -0.7874 0.4064)
			(end -0.7874 -0.4064)
			(stroke
				(width 0.1524)
				(type default)
			)
			(layer "F.SilkS")
		)
		(fp_line
			(start -0.12065 -0.305054)
			(end -0.12065 -0.2794)
			(stroke
				(width 0.1)
				(type default)
			)
			(layer "F.Fab")
		)
		(fp_line
			(start -0.67945 -0.305054)
			(end -0.12065 -0.305054)
			(stroke
				(width 0.1)
				(type default)
			)
			(layer "F.Fab")
		)
		(fp_line
			(start 0.67945 -0.3048)
			(end 0.67945 0.3048)
			(stroke
				(width 0.1)
				(type default)
			)
			(layer "F.Fab")
		)
		(fp_line
			(start 0.12065 -0.3048)
			(end 0.67945 -0.3048)
			(stroke
				(width 0.1)
				(type default)
			)
			(layer "F.Fab")
		)
		(fp_line
			(start 0.12065 -0.2794)
			(end 0.12065 -0.3048)
			(stroke
				(width 0.1)
				(type default)
			)
			(layer "F.Fab")
		)
		(fp_line
			(start -0.12065 -0.2794)
			(end 0.12065 -0.2794)
			(stroke
				(width 0.1)
				(type default)
			)
			(layer "F.Fab")
		)
		(fp_line
			(start 0.120396 0.2794)
			(end -0.12065 0.2794)
			(stroke
				(width 0.1)
				(type default)
			)
			(layer "F.Fab")
		)
		(fp_line
			(start -0.12065 0.2794)
			(end -0.12065 0.3048)
			(stroke
				(width 0.1)
				(type default)
			)
			(layer "F.Fab")
		)
		(fp_line
			(start 0.67945 0.3048)
			(end 0.120396 0.3048)
			(stroke
				(width 0.1)
				(type default)
			)
			(layer "F.Fab")
		)
		(fp_line
			(start 0.120396 0.3048)
			(end 0.120396 0.2794)
			(stroke
				(width 0.1)
				(type default)
			)
			(layer "F.Fab")
		)
		(fp_line
			(start -0.12065 0.3048)
			(end -0.67945 0.3048)
			(stroke
				(width 0.1)
				(type default)
			)
			(layer "F.Fab")
		)
		(fp_line
			(start -0.67945 0.3048)
			(end -0.67945 -0.305054)
			(stroke
				(width 0.1)
				(type default)
			)
			(layer "F.Fab")
		)
		(pad "1" smd circle
			(at -0.40005 0 90)
			(size 0 0)
			(layers "F.Cu" "F.Mask" "F.Paste")
			(net "P3V3_AUX")
		)
		(pad "2" smd circle
			(at 0.40005 0 90)
			(size 0 0)
			(layers "F.Cu" "F.Mask" "F.Paste")
			(net "GPU_3V3IO_RSVD3_FFU_ISO")
		)
	)
	(footprint ""
		(layer "F.Cu")
		(at 179.09032 -408.203908)
		(property "Reference" "R4531"
			(at 0 0 0)
			(layer "F.SilkS")
			(hide yes)
			(effects
				(font
					(size 1.27 1.27)
				)
			)
		)
		(property "Value" ""
			(at 0 0 0)
			(layer "F.Fab")
			(effects
				(font
					(size 1.27 1.27)
				)
			)
		)
		(duplicate_pad_numbers_are_jumpers no)
		(fp_line
			(start -0.7874 -0.4064)
			(end 0.7874 -0.4064)
			(stroke
				(width 0.1524)
				(type default)
			)
			(layer "F.SilkS")
		)
		(fp_line
			(start -0.7874 0.4064)
			(end -0.7874 -0.4064)
			(stroke
				(width 0.1524)
				(type default)
			)
			(layer "F.SilkS")
		)
		(fp_line
			(start 0.7874 -0.4064)
			(end 0.7874 0.4064)
			(stroke
				(width 0.1524)
				(type default)
			)
			(layer "F.SilkS")
		)
		(fp_line
			(start 0.7874 0.4064)
			(end -0.7874 0.4064)
			(stroke
				(width 0.1524)
				(type default)
			)
			(layer "F.SilkS")
		)
		(fp_line
			(start -0.67945 -0.305054)
			(end -0.12065 -0.305054)
			(stroke
				(width 0.1)
				(type default)
			)
			(layer "F.Fab")
		)
		(fp_line
			(start -0.67945 0.3048)
			(end -0.67945 -0.305054)
			(stroke
				(width 0.1)
				(type default)
			)
			(layer "F.Fab")
		)
		(fp_line
			(start -0.12065 -0.305054)
			(end -0.12065 -0.2794)
			(stroke
				(width 0.1)
				(type default)
			)
			(layer "F.Fab")
		)
		(fp_line
			(start -0.12065 -0.2794)
			(end 0.12065 -0.2794)
			(stroke
				(width 0.1)
				(type default)
			)
			(layer "F.Fab")
		)
		(fp_line
			(start -0.12065 0.2794)
			(end -0.12065 0.3048)
			(stroke
				(width 0.1)
				(type default)
			)
			(layer "F.Fab")
		)
		(fp_line
			(start -0.12065 0.3048)
			(end -0.67945 0.3048)
			(stroke
				(width 0.1)
				(type default)
			)
			(layer "F.Fab")
		)
		(fp_line
			(start 0.120396 0.2794)
			(end -0.12065 0.2794)
			(stroke
				(width 0.1)
				(type default)
			)
			(layer "F.Fab")
		)
		(fp_line
			(start 0.120396 0.3048)
			(end 0.120396 0.2794)
			(stroke
				(width 0.1)
				(type default)
			)
			(layer "F.Fab")
		)
		(fp_line
			(start 0.12065 -0.3048)
			(end 0.67945 -0.3048)
			(stroke
				(width 0.1)
				(type default)
			)
			(layer "F.Fab")
		)
		(fp_line
			(start 0.12065 -0.2794)
			(end 0.12065 -0.3048)
			(stroke
				(width 0.1)
				(type default)
			)
			(layer "F.Fab")
		)
		(fp_line
			(start 0.67945 -0.3048)
			(end 0.67945 0.3048)
			(stroke
				(width 0.1)
				(type default)
			)
			(layer "F.Fab")
		)
		(fp_line
			(start 0.67945 0.3048)
			(end 0.120396 0.3048)
			(stroke
				(width 0.1)
				(type default)
			)
			(layer "F.Fab")
		)
		(pad "1" smd circle
			(at -0.40005 0)
			(size 0 0)
			(layers "F.Cu" "F.Mask" "F.Paste")
			(net "SMB_SML1_PMBUS_HSC_SDA_R3")
		)
		(pad "2" smd circle
			(at 0.40005 0)
			(size 0 0)
			(layers "F.Cu" "F.Mask" "F.Paste")
			(net "SMB_SML1_PMBUS_HSC_SDA")
		)
	)
)
